FILE_TYPE = CONNECTIVITY;
{Allegro Design Entry HDL 17.4-2019 S026 (4007227) 1/17/2022}
"PAGE_NUMBER" = 336;
0"NC";
1"GND\g";
2"GND\g";
3"GND\g";
4"GND\g";
5"GND\g";
6"GND\g"VOLTAGE"0"CDS_PHYS_NET_NAME"GND";
7"GND\g"VOLTAGE"0"CDS_PHYS_NET_NAME"GND";
8"GND\g";
9"GND\g";
10"GND\g";
11"OCP_SFF_AUX_PWR_EN"CDS_PHYS_NET_NAME"OCP_V3_2_AUX_PWR_EN";
12"OCP_SFF_AUX_PWR_EN"CDS_PHYS_NET_NAME"OCP_SFF_RBT_ARB_IN";
13"RST_SMB_SWITCH_N"CDS_PHYS_NET_NAME"RST_SMB_SWITCH_N";
14"OCP_SFF_AUX_PWR_EN_R2"CDS_PHYS_NET_NAME"OCP_V3_2_AUX_PWR_EN_R4";
15"RST_SMB_OCP_SFF_N";
16"RST_HP_OCP_SFF_R_N";
17"P3V3_AUX\g";
18"FM_NCSI_OCP_SFF_R_OE";
19"OCP_SFF_AUX_PWR_EN_R1";
20"FM_OCP_SFF_PWR_GOOD"CDS_PHYS_NET_NAME"OCP_SFF_RBT_ARB_IN";
21"P3V3_AUX\g";
22"FB_BMC_ISOLATE_R1";
23"FB_BMC_ISOLATE";
24"GND\g";
25"GND\g";
26"P3V3_AUX\g"$PHYS_NET_NAME"P3V3_AUX"VOLTAGE"3.3"CDS_PHYS_NET_NAME"P3V3_AUX"$PHYS_NET_NAME"P3V3_AUX"VOLTAGE"3.3"CDS_PHYS_NET_NAME"P3V3_AUX";
27"P3V3_AUX\g"$PHYS_NET_NAME"P3V3_AUX"VOLTAGE"3.3"CDS_PHYS_NET_NAME"P3V3_AUX"$PHYS_NET_NAME"P3V3_AUX"VOLTAGE"3.3"CDS_PHYS_NET_NAME"P3V3_AUX";
28"OCP_SFF_RBT_ARB_IN_R"CDS_PHYS_NET_NAME"OCP_SFF_RBT_ARB_IN";
29"OCP_SFF_RBT_ARB_IN";
30"RMII_OCP_BMC_RXD_0";
31"RMII_OCP_BMC_CRSDV";
32"RMII_OCP_BMC_RXD_1";
33"NCSI_BMC_RXD1_R";
34"NCSI_BMC_RXD0_R"CDS_PHYS_NET_NAME"NCSI_OCP_SFF_RXD0";
35"NCSI_BMC_CRS_DV_R"CDS_PHYS_NET_NAME"NCSI_OCP_SFF_CRS_DV";
36"OCP_SFF_RBT_ARB_OUT";
37"NCSI_BMC_TXD0_R";
38"NCSI_OCP_SFF_TX_EN";
39"RMII_BMC_OCP_TX_EN";
40"NCSI_BMC_TXD1_R";
41"NCSI_OCP_SFF_TXD1";
42"RMII_BMC_OCP_TX_EN";
43"NCSI_OCP_SFF_RXD0"CDS_PHYS_NET_NAME"NCSI_OCP_SFF_RXD0";
44"RMII_BMC_OCP_TXD_0";
45"RMII_BMC_OCP_TXD_1";
46"OCP_SFF_ISO1_RBT_ARB_IN"CDS_PHYS_NET_NAME"OCP_SFF_RBT_ARB_IN";
47"RMII_OCP_BMC_RXD_1";
48"RMII_OCP_BMC_CRSDV";
49"RMII_OCP_BMC_RXD_0";
50"RMII_BMC_OCP_TXD_1";
51"RMII_BMC_OCP_TXD_0";
52"RMII_BMC_OCP_RX_ER";
53"OCP_SFF_ISO2_RBT_ARB_OUT";
54"NCSI_OCP_SFF_TXD0";
55"NCSI_BMC_TX_EN_R";
56"OCP_SFF_ISO_BIF0_EN"CDS_PHYS_NET_NAME"NCSI_OCP_SFF_CRS_DV";
57"OCP_SFF_ISO_BIF2_EN"CDS_PHYS_NET_NAME"NCSI_OCP_SFF_CRS_DV";
58"OCP_SFF_ISO_BIF1_EN"CDS_PHYS_NET_NAME"NCSI_OCP_SFF_CRS_DV";
59"NCSI_OCP_SFF_RXD1";
60"NCSI_OCP_SFF_CRS_DV"CDS_PHYS_NET_NAME"NCSI_OCP_SFF_CRS_DV";
%"74CBTLV3126PW"
"1","(-225,6700)","2","pure_quanta","I1";
;
LOCATION"U67"
$SEC"1"
CDS_SEC"1"
PART_TYPE"SMLF"
VALUE"74CBTLV3126PW"
MATERIAL"IC"
CDS_LIB"pure_quanta"
NEEDS_NO_SIZE"TRUE"
CDS_LMAN_SYM_OUTLINE"-250,350,250,-350"
PART_NUMBER"AL003126K08";
"VCC"
$PN"14"27;
"4OE"
$PN"13"23;
"4A"
$PN"12"28;
"4B"
$PN"11"46;
"3OE"
$PN"10"23;
"3A"
$PN"9"35;
"GND"
$PN"7"7;
"1A"
$PN"2"33;
"2B"
$PN"6"43;
"1B"
$PN"3"59;
"2OE"
$PN"4"23;
"1OE"
$PN"1"23;
"3B"
$PN"8"60;
"2A"
$PN"5"34;
%"Q_RES"
"1","(1450,6600)","0","pure_quanta","I100";
;
LOCATION"R72"
$SEC"1"
CDS_SEC"1"
VALUE"22"
MATERIAL"CHIP"
WATTAGE"1/16W"
TOLERANCE"1%"
PACK_TYPE"0402LF"
CDS_LIB"pure_quanta"
PART_NUMBER"CS02202FB02";
"B"
$PN"2"30;
"A"
$PN"1"34;
%"Q_RES"
"1","(1450,6450)","0","pure_quanta","I101";
;
LOCATION"R73"
$SEC"1"
CDS_SEC"1"
VALUE"22"
MATERIAL"CHIP"
WATTAGE"1/16W"
TOLERANCE"1%"
PACK_TYPE"0402LF"
CDS_LIB"pure_quanta"
PART_NUMBER"CS02202FB02";
"B"
$PN"2"32;
"A"
$PN"1"33;
%"Q_RES"
"1","(1450,5325)","0","pure_quanta","I102";
;
LOCATION"R74"
$SEC"1"
CDS_SEC"1"
VALUE"0"
MATERIAL"CHIP"
TOLERANCE"5%"
CDS_LIB"pure_quanta"
PACK_TYPE"0402LF"
WATTAGE"1/16W"
PART_NUMBER"CS00002JB13";
"B"
$PN"2"39;
"A"
$PN"1"55;
%"Q_RES"
"1","(1450,5175)","0","pure_quanta","I103";
;
LOCATION"R75"
$SEC"1"
CDS_SEC"1"
MATERIAL"CHIP"
VALUE"0"
TOLERANCE"5%"
WATTAGE"1/16W"
PACK_TYPE"0402LF"
CDS_LIB"pure_quanta"
PART_NUMBER"CS00002JB13";
"B"
$PN"2"44;
"A"
$PN"1"37;
%"Q_RES"
"1","(1450,5025)","0","pure_quanta","I104";
;
LOCATION"R76"
$SEC"1"
CDS_SEC"1"
VALUE"0"
MATERIAL"CHIP"
TOLERANCE"5%"
WATTAGE"1/16W"
PACK_TYPE"0402LF"
CDS_LIB"pure_quanta"
PART_NUMBER"CS00002JB13";
"B"
$PN"2"45;
"A"
$PN"1"40;
%"Q_RES"
"1","(-3450,3950)","0","pure_quanta","I119";
;
LOCATION"R1719"
$SEC"1"
CDS_SEC"1"
MATERIAL"CHIP"
WATTAGE"1/16W"
PACK_TYPE"0402LF"
VALUE"33.2"
TOLERANCE"1%"
CDS_LIB"pure_quanta"
PART_NUMBER"CS03322FB03";
"B"
$PN"2"19;
"A"
$PN"1"12;
%"Q_RES"
"2","(2375,2100)","0","pure_quanta","I122";
;
LOCATION"R1898"
$SEC"1"
CDS_SEC"1"
PACK_TYPE"0402LF"
MATERIAL"CHIP"
WATTAGE"1/16W"
VALUE"100"
TOLERANCE"1%"
CDS_LIB"pure_quanta"
PART_NUMBER"CS11002FB07";
"A"
$PN"1"57;
"B"
$PN"2"24;
%"Q_RES"
"2","(1875,2100)","0","pure_quanta","I123";
;
LOCATION"R1896"
$SEC"1"
CDS_SEC"1"
VALUE"100"
PACK_TYPE"0402LF"
WATTAGE"1/16W"
MATERIAL"CHIP"
TOLERANCE"1%"
CDS_LIB"pure_quanta"
PART_NUMBER"CS11002FB07";
"A"
$PN"1"56;
"B"
$PN"2"24;
%"Q_RES"
"2","(2125,2100)","0","pure_quanta","I124";
;
LOCATION"R1897"
$SEC"1"
CDS_SEC"1"
WATTAGE"1/16W"
TOLERANCE"1%"
VALUE"100"
MATERIAL"CHIP"
PACK_TYPE"0402LF"
CDS_LIB"pure_quanta"
PART_NUMBER"CS11002FB07";
"A"
$PN"1"58;
"B"
$PN"2"24;
%"UNIVERSAL_GND"
"1","(2375,1825)","0","pure_quanta_power","I125";
;
CDS_LIB"pure_quanta_power"
HDL_POWER"GND";
"A"24;
%"Q_RES"
"1","(3025,3725)","0","pure_quanta","I129";
;
LOCATION"R84"
$SEC"1"
CDS_SEC"1"
MATERIAL"CHIP"
VALUE"100K"
TOLERANCE"1%"
PACK_TYPE"0402LF"
WATTAGE"1/16W"
CDS_LIB"pure_quanta"
PART_NUMBER"CS41002FB09";
"B"
$PN"2"25;
"A"
$PN"1"50;
%"UNIVERSAL_GND"
"1","(3625,3325)","0","pure_quanta_power","I130";
;
CDS_LIB"pure_quanta_power"
HDL_POWER"GND";
"A"25;
%"Q_RES"
"1","(3025,4475)","0","pure_quanta","I131";
;
LOCATION"R77"
$SEC"1"
CDS_SEC"1"
VALUE"100K"
WATTAGE"1/16W"
MATERIAL"CHIP"
TOLERANCE"1%"
PACK_TYPE"0402LF"
CDS_LIB"pure_quanta"
PART_NUMBER"CS41002FB09";
"B"
$PN"2"25;
"A"
$PN"1"48;
%"Q_RES"
"1","(3025,4325)","0","pure_quanta","I132";
;
LOCATION"R79"
$SEC"1"
CDS_SEC"1"
TOLERANCE"1%"
MATERIAL"CHIP"
VALUE"100K"
PACK_TYPE"0402LF"
WATTAGE"1/16W"
CDS_LIB"pure_quanta"
PART_NUMBER"CS41002FB09";
"B"
$PN"2"25;
"A"
$PN"1"49;
%"Q_RES"
"1","(3025,4175)","0","pure_quanta","I133";
;
LOCATION"R80"
$SEC"1"
CDS_SEC"1"
VALUE"100K"
MATERIAL"CHIP"
TOLERANCE"1%"
PACK_TYPE"0402LF"
WATTAGE"1/16W"
CDS_LIB"pure_quanta"
PART_NUMBER"CS41002FB09";
"B"
$PN"2"25;
"A"
$PN"1"47;
%"Q_RES"
"1","(3025,4025)","0","pure_quanta","I134";
;
LOCATION"R82"
$SEC"1"
CDS_SEC"1"
MATERIAL"CHIP"
TOLERANCE"1%"
VALUE"100K"
CDS_LIB"pure_quanta"
WATTAGE"1/16W"
PACK_TYPE"0402LF"
PART_NUMBER"CS41002FB09";
"B"
$PN"2"25;
"A"
$PN"1"42;
%"Q_RES"
"1","(3025,3875)","0","pure_quanta","I135";
;
LOCATION"R83"
$SEC"1"
CDS_SEC"1"
MATERIAL"CHIP"
TOLERANCE"1%"
VALUE"100K"
PACK_TYPE"0402LF"
WATTAGE"1/16W"
CDS_LIB"pure_quanta"
PART_NUMBER"CS41002FB09";
"B"
$PN"2"25;
"A"
$PN"1"51;
%"Q_RES"
"1","(3025,3550)","0","pure_quanta","I136";
;
LOCATION"R87"
$SEC"1"
CDS_SEC"1"
PACK_TYPE"0402LF"
TOLERANCE"1%"
WATTAGE"1/16W"
VALUE"1K"
MATERIAL"CHIP"
CDS_LIB"pure_quanta"
PART_NUMBER"CS21002FB06";
"B"
$PN"2"25;
"A"
$PN"1"52;
%"UNIVERSAL_GND"
"1","(-2350,2475)","0","pure_quanta_power","I146";
;
CDS_LIB"pure_quanta_power"
HDL_POWER"GND";
"A"1;
%"Q_CAP"
"1","(-2350,2700)","2","pure_quanta","I147";
;
LOCATION"C1840"
$SEC"1"
CDS_SEC"1"
PACK_TYPE"0402"
VOLTAGE"25V"
VALUE"0.1UF"
MATERIAL"X7R"
TOLERANCE"10%"
CDS_LIB"pure_quanta"
PART_NUMBER"CH4104K1B00";
"B"
$PN"2"1;
"A"
$PN"1"17;
%"UNIVERSAL_GND"
"1","(-975,5575)","0","pure_quanta_power","I15";
;
CDS_LIB"pure_quanta_power"
HDL_POWER"GND";
"A"2;
%"UNIVERSAL_POWER"
"1","(-2350,3000)","0","pure_quanta_power","I150";
;
HDL_POWER"P3V3_AUX"
CDS_LIB"pure_quanta_power";
"A"17;
%"UNIVERSAL_GND"
"1","(-1125,1825)","0","pure_quanta_power","I151";
;
CDS_LIB"pure_quanta_power"
HDL_POWER"GND";
"A"3;
%"Q_RES"
"2","(-1125,2050)","0","pure_quanta","I152";
;
LOCATION"R3232"
$SEC"1"
CDS_SEC"1"
MATERIAL"CHIP"
VALUE"100K"
PACK_TYPE"0402LF"
TOLERANCE"1%"
WATTAGE"1/16W"
CDS_LIB"pure_quanta"
PART_NUMBER"CS41002FB09";
"A"
$PN"1"16;
"B"
$PN"2"3;
%"Q_RES"
"1","(-800,2275)","0","pure_quanta","I153";
;
LOCATION"R3233"
$SEC"1"
CDS_SEC"1"
VALUE"0"
TOLERANCE"5%"
WATTAGE"1/16W"
PACK_TYPE"0402LF"
MATERIAL"CHIP"
CDS_LIB"pure_quanta"
PART_NUMBER"CS00002JB13";
"B"
$PN"2"15;
"A"
$PN"1"16;
%"Q_RES"
"1","(2900,6725)","1","pure_quanta","I156";
;
LOCATION"R3237"
$SEC"1"
CDS_SEC"1"
VALUE"0"
MATERIAL"CHIP"
CDS_LIB"pure_quanta"
WATTAGE"1/16W"
PACK_TYPE"0402LF"
TOLERANCE"5%"
PART_NUMBER"CS00002JB13";
"B"
$PN"2"28;
"A"
$PN"1"36;
%"74LVC1G126SE7"
"1","(-1650,4000)","0","pure_quanta","I157";
;
LOCATION"U66"
SEC"1"
PART_TYPE"SMLF"
VALUE"74LVC1G126SE-7"
MATERIAL"IC"
CDS_LIB"pure_quanta"
CDS_LMAN_SYM_OUTLINE"-100,100,100,-100"
SEC_TYPE""
NEEDS_NO_SIZE"TRUE"
PART_NUMBER"AL1G0126009";
"OE"
$PN"1"19;
"GND"
$PN"3"4;
"VCC"
$PN"5"21;
"Y"
$PN"4"22;
"A"
$PN"2"20;
%"UNIVERSAL_GND"
"1","(-1650,3625)","0","pure_quanta_power","I158";
;
CDS_LIB"pure_quanta_power"
HDL_POWER"GND";
"A"4;
%"74LVC1G126SE7"
"1","(-1975,2275)","0","pure_quanta","I159";
;
LOCATION"U224"
$SEC"1"
CDS_SEC"1"
PART_TYPE"SMLF"
VALUE"74LVC1G126SE-7"
MATERIAL"IC"
CDS_LIB"pure_quanta"
CDS_LMAN_SYM_OUTLINE"-100,100,100,-100"
NEEDS_NO_SIZE"TRUE"
PART_NUMBER"AL1G0126009";
"OE"
$PN"1"14;
"GND"
$PN"3"5;
"VCC"
$PN"5"17;
"Y"
$PN"4"16;
"A"
$PN"2"13;
%"Q_CAP"
"1","(-975,5800)","2","pure_quanta","I16";
;
LOCATION"C641"
$SEC"1"
CDS_SEC"1"
TOLERANCE"10%"
PACK_TYPE"0402"
MATERIAL"X7R"
VOLTAGE"25V"
VALUE"0.1UF"
CDS_LIB"pure_quanta"
PART_NUMBER"CH4104K1B00";
"B"
$PN"2"2;
"A"
$PN"1"26;
%"Q_RES"
"1","(-3350,2225)","0","pure_quanta","I160";
;
LOCATION"R3231"
$SEC"1"
CDS_SEC"1"
PACK_TYPE"0402LF"
WATTAGE"1/16W"
VALUE"33.2"
TOLERANCE"1%"
MATERIAL"CHIP"
CDS_LIB"pure_quanta"
PART_NUMBER"CS03322FB03";
"B"
$PN"2"14;
"A"
$PN"1"11;
%"UNIVERSAL_GND"
"1","(-1975,1900)","0","pure_quanta_power","I162";
;
CDS_LIB"pure_quanta_power"
HDL_POWER"GND";
"A"5;
%"Q_RES"
"1","(-425,4000)","0","pure_quanta","I164";
;
LOCATION"R2473"
$SEC"1"
CDS_SEC"1"
TOLERANCE"5%"
PACK_TYPE"0402LF"
MATERIAL"CHIP"
WATTAGE"1/16W"
VALUE"0"
CDS_LIB"pure_quanta"
PART_NUMBER"CS00002JB13";
"B"
$PN"2"23;
"A"
$PN"1"22;
%"Q_RES"
"1","(-525,3475)","0","pure_quanta","I165";
;
LOCATION"R2474"
$SEC"1"
CDS_SEC"1"
TOLERANCE"5%"
MATERIAL"EMPTY"
VALUE"0"
PACK_TYPE"0402LF"
WATTAGE"1/16W"
CDS_LIB"pure_quanta"
PART_NUMBER"CS00002JB13";
"B"
$PN"2"23;
"A"
$PN"1"18;
%"74CBTLV3126PW"
"1","(-225,5275)","2","pure_quanta","I2";
;
LOCATION"U7"
$SEC"1"
CDS_SEC"1"
PART_TYPE"SMLF"
MATERIAL"IC"
VALUE"74CBTLV3126PW"
CDS_LIB"pure_quanta"
NEEDS_NO_SIZE"TRUE"
CDS_LMAN_SYM_OUTLINE"-250,350,250,-350"
PART_NUMBER"AL003126K08";
"VCC"
$PN"14"26;
"4OE"
$PN"13"23;
"4A"
$PN"12"36;
"4B"
$PN"11"53;
"3OE"
$PN"10"23;
"3A"
$PN"9"55;
"GND"
$PN"7"6;
"1A"
$PN"2"40;
"2B"
$PN"6"54;
"1B"
$PN"3"41;
"2OE"
$PN"4"23;
"1OE"
$PN"1"23;
"3B"
$PN"8"38;
"2A"
$PN"5"37;
%"UNIVERSAL_POWER"
"1","(-775,6125)","0","pure_quanta_power","I43";
;
HDL_POWER"P3V3_AUX"
CDS_LIB"pure_quanta_power";
"A"26;
%"UNIVERSAL_GND"
"1","(-775,4850)","0","pure_quanta_power","I44";
;
CDS_LIB"pure_quanta_power"
HDL_POWER"GND";
"A"6;
%"UNIVERSAL_GND"
"1","(-775,6275)","0","pure_quanta_power","I45";
;
CDS_LIB"pure_quanta_power"
HDL_POWER"GND";
"A"7;
%"UNIVERSAL_POWER"
"1","(-775,7550)","0","pure_quanta_power","I46";
;
HDL_POWER"P3V3_AUX"
CDS_LIB"pure_quanta_power";
"A"27;
%"Q_CAP"
"1","(-975,7225)","2","pure_quanta","I47";
;
LOCATION"C640"
$SEC"1"
CDS_SEC"1"
VOLTAGE"25V"
VALUE"0.1UF"
MATERIAL"X7R"
PACK_TYPE"0402"
TOLERANCE"10%"
CDS_LIB"pure_quanta"
PART_NUMBER"CH4104K1B00";
"B"
$PN"2"8;
"A"
$PN"1"27;
%"UNIVERSAL_GND"
"1","(-975,7000)","0","pure_quanta_power","I48";
;
CDS_LIB"pure_quanta_power"
HDL_POWER"GND";
"A"8;
%"UNIVERSAL_POWER"
"1","(-2075,4650)","0","pure_quanta_power","I54";
;
HDL_POWER"P3V3_AUX"
CDS_LIB"pure_quanta_power";
"A"21;
%"Q_RES"
"2","(-175,3800)","0","pure_quanta","I56";
;
LOCATION"R1289"
$SEC"1"
CDS_SEC"1"
WATTAGE"1/16W"
VALUE"100K"
MATERIAL"CHIP"
TOLERANCE"1%"
PACK_TYPE"0402LF"
CDS_LIB"pure_quanta"
PART_NUMBER"CS41002FB09";
"A"
$PN"1"23;
"B"
$PN"2"9;
%"UNIVERSAL_GND"
"1","(-175,3575)","0","pure_quanta_power","I57";
;
CDS_LIB"pure_quanta_power"
HDL_POWER"GND";
"A"9;
%"UNIVERSAL_GND"
"1","(-2075,4200)","0","pure_quanta_power","I58";
;
CDS_LIB"pure_quanta_power"
HDL_POWER"GND";
"A"10;
%"Q_CAP"
"1","(-2075,4425)","2","pure_quanta","I59";
;
LOCATION"C639"
$SEC"1"
CDS_SEC"1"
VALUE"0.1UF"
VOLTAGE"25V"
TOLERANCE"10%"
MATERIAL"X7R"
PACK_TYPE"0402"
CDS_LIB"pure_quanta"
PART_NUMBER"CH4104K1B00";
"B"
$PN"2"10;
"A"
$PN"1"21;
%"Q_RES"
"1","(3050,6900)","0","pure_quanta","I98";
;
LOCATION"R1290"
$SEC"1"
CDS_SEC"1"
VALUE"22"
WATTAGE"1/16W"
PACK_TYPE"0402LF"
MATERIAL"EMPTY"
TOLERANCE"1%"
CDS_LIB"pure_quanta"
PART_NUMBER"CS02202FB02";
"B"
$PN"2"29;
"A"
$PN"1"28;
%"Q_RES"
"1","(1450,6750)","0","pure_quanta","I99";
;
LOCATION"R59"
$SEC"1"
CDS_SEC"1"
MATERIAL"CHIP"
VALUE"22"
CDS_LIB"pure_quanta"
PACK_TYPE"0402LF"
TOLERANCE"1%"
WATTAGE"1/16W"
PART_NUMBER"CS02202FB02";
"B"
$PN"2"31;
"A"
$PN"1"35;
END.
